FILE_TYPE = MULTI_PHYS_TABLE;
PART 'FUSE'
{=======================================================================================================================================================================}
:PACK_TYPE |MATERIAL  |PART_NUMBER      = EnvComp                  | PART_NUMBER  |JEDEC_TYPE  |CLASS  |DESCRIPTION                            |HEIGHT      |COMPONENT_TYPE  |LEAD_LENGTH  | LPID   | SPEED_URL | Status |RPL| AML | Bus_Unit | Days ;
{=======================================================================================================================================================================}
'SMLF'     | 'IC'     | 'C94311-006'(!) = 'YES;YES;UNK;UNK;ok;VLD' | 'C94311-006' | 'SFU1812A' | 'IC'  | '1.5A 12V'                            | '0.019 IN' | 'CHIP'         | ''          | ''     | 'http://speed.intel.com:8081/speed/module/pdm/item/pdm_item_detail_direct.asp?item_cde=C94311-006&item_rev=01&url_param=unused' | 'Conditional' | 'NO' | '2' | 'SMO_BOARDS' | '???' 
'SMLF'     | 'EMPTY'  | 'C94311-006'(!) = 'YES;YES;UNK;UNK;ok;VLD' | 'C94311-006' | 'SFU1812A' | 'IO'  | '1.5A 12V'                            | '0.019 IN' | 'CHIP'         | ''          | ''     | 'http://speed.intel.com:8081/speed/module/pdm/item/pdm_item_detail_direct.asp?item_cde=C94311-006&item_rev=01&url_param=unused' | 'Conditional' | 'NO' | '2' | 'SMO_BOARDS' | '???' 
'SM'       | 'IC'     | 'C94311-016'(!) = 'YES;YES;UNK;UNK;ok;CIP' | 'C94311-016' | 'SFU1812A' | 'IC'  | 'POLYSWITCH,SMT,1812,2.600A,16V'      | '0.060 IN' | 'CHIP'         | ''          | '1144' | 'http://speed.intel.com:8081/speed/module/pdm/item/pdm_item_detail_direct.asp?item_cde=C94311-016&item_rev=01&url_param=unused' | 'Conditional' | 'NO' | '1' | 'SMO_BOARDS' | '???' 
'SM'       | 'EMPTY'  | 'C94311-016'(!) = 'YES;YES;UNK;UNK;ok;CIP' | 'C94311-016' | 'SFU1812A' | 'IO'  | 'POLYSWITCH,SMT,1812,2.600A,16V'      | '0.060 IN' | 'CHIP'         | ''          | '1144' | 'http://speed.intel.com:8081/speed/module/pdm/item/pdm_item_detail_direct.asp?item_cde=C94311-016&item_rev=01&url_param=unused' | 'Conditional' | 'NO' | '1' | 'SMO_BOARDS' | '???' 
'SMT'      | 'IC'     | 'H45581-001'(!) = ''                       | 'H45581-001' | 'SFU0603B' | 'IC'  | 'POLYSWITCH,SMT,0603,0.35A,6V'        | '0.061 IN' | 'CHIP0603'     | ''          | '3802' | 'http://speed.intel.com:8081/speed/module/pdm/item/pdm_item_detail_direct.asp?item_cde=H45581-001&item_rev=01&url_param=unused' | '' | '' | '' | '' | '' 
'SMT'      | 'EMPTY'  | 'H45581-001'(!) = ''                       | 'H45581-001' | 'SFU0603B' | 'IO'  | 'POLYSWITCH,SMT,0603,0.35A,6V'        | '0.061 IN' | 'CHIP0603'     | ''          | '3802' | 'http://speed.intel.com:8081/speed/module/pdm/item/pdm_item_detail_direct.asp?item_cde=H45581-001&item_rev=01&url_param=unused' | '' | '' | '' | '' | ''
END_PART
END.
